# S9S_MB_2U (Grand Teton) — schematic netlist excerpt (pin names and nets, part order shuffled) for the footprints in the layout excerpt that follows; sources: Cadence DE-HDL packaged netlist, KiCad conversion of 03242023_DA0F0TMBIJ0_F0T_Motherboard_J_brd_V01_OCP.brd

R4549  Q_RES  4.7K 5% EMPTY  pkg 0402LF  page 145 : A = P3V3_AUX ; B = SWB_HSC_EN_BUF_R
PR91  Q_RES  11.8K 0.1% CHIP  pkg 0402LF  page 258 : A = P5V_AUX_FB ; B = GND
C867  Q_CAP_DIFFBUS  DIFF BUS_0.22UF 6.3V 20% X6S  pkg C0201  page 174 : \1\ = P5E_CPU0_PE1_TX_C_DP<1> ; \2\ = P5E_CPU0_PE1_TX_DP<1>

(kicad_pcb
	(version 20260206)
	(generator "pcbnew")
	(generator_version "10.0")
	(general
		(thickness 1.6)
		(legacy_teardrops no)
	)
	(paper "A4")
	(title_block
		(title "03242023_DA0F0TMBIJ0_F0T_Motherboard_J_brd_V01_OCP.brd")
		(comment 1 "Grand Teton / footprints 3189-3191 of 6105")
	)
	(layers
		(0 "F.Cu" signal "TOP")
		(4 "In1.Cu" signal "GND")
		(6 "In2.Cu" signal "IN1")
		(8 "In3.Cu" signal "GND1")
		(10 "In4.Cu" signal "IN2")
		(12 "In5.Cu" signal "GND2")
		(14 "In6.Cu" signal "IN3")
		(16 "In7.Cu" signal "GND3")
		(18 "In8.Cu" signal "VCC")
		(20 "In9.Cu" signal "VCC1")
		(22 "In10.Cu" signal "GND4")
		(24 "In11.Cu" signal "IN4")
		(26 "In12.Cu" signal "GND5")
		(28 "In13.Cu" signal "IN5")
		(30 "In14.Cu" signal "GND6")
		(32 "In15.Cu" signal "IN6")
		(34 "In16.Cu" signal "GND7")
		(2 "B.Cu" signal "BOTTOM")
		(9 "F.Adhes" user "F.Adhesive")
		(11 "B.Adhes" user "B.Adhesive")
		(13 "F.Paste" user "Package Geometry/Pastemask Top")
		(15 "B.Paste" user "Package Geometry/Pastemask Bottom")
		(5 "F.SilkS" user "Ref Des/Silkscreen Top")
		(7 "B.SilkS" user "Ref Des/Silkscreen Bottom")
		(1 "F.Mask" user "Board Geometry/Soldermask Top")
		(3 "B.Mask" user "Board Geometry/Soldermask Bottom")
		(17 "Dwgs.User" user "User.Drawings")
		(19 "Cmts.User" user "User.Comments")
		(21 "Eco1.User" user "User.Eco1")
		(23 "Eco2.User" user "User.Eco2")
		(25 "Edge.Cuts" user "Board Geometry/Outline")
		(27 "Margin" user)
		(31 "F.CrtYd" user "Package Geometry/Place Bound Top")
		(29 "B.CrtYd" user "Package Geometry/Place Bound Bottom")
		(35 "F.Fab" user "Ref Des/Assembly Top")
		(33 "B.Fab" user "Ref Des/Assembly Bottom")
	)
	(footprint ""
		(layer "F.Cu")
		(at 362.1405 -409.654248 180)
		(property "Reference" "R4549"
			(at 0 0 180)
			(layer "F.SilkS")
			(hide yes)
			(effects
				(font
					(size 1.27 1.27)
				)
			)
		)
		(property "Value" ""
			(at 0 0 180)
			(layer "F.Fab")
			(effects
				(font
					(size 1.27 1.27)
				)
			)
		)
		(duplicate_pad_numbers_are_jumpers no)
		(fp_line
			(start 0.7874 0.4064)
			(end -0.7874 0.4064)
			(stroke
				(width 0.1524)
				(type default)
			)
			(layer "F.SilkS")
		)
		(fp_line
			(start 0.7874 -0.4064)
			(end 0.7874 0.4064)
			(stroke
				(width 0.1524)
				(type default)
			)
			(layer "F.SilkS")
		)
		(fp_line
			(start -0.7874 0.4064)
			(end -0.7874 -0.4064)
			(stroke
				(width 0.1524)
				(type default)
			)
			(layer "F.SilkS")
		)
		(fp_line
			(start -0.7874 -0.4064)
			(end 0.7874 -0.4064)
			(stroke
				(width 0.1524)
				(type default)
			)
			(layer "F.SilkS")
		)
		(fp_line
			(start 0.67945 0.3048)
			(end 0.120396 0.3048)
			(stroke
				(width 0.1)
				(type default)
			)
			(layer "F.Fab")
		)
		(fp_line
			(start 0.67945 -0.3048)
			(end 0.67945 0.3048)
			(stroke
				(width 0.1)
				(type default)
			)
			(layer "F.Fab")
		)
		(fp_line
			(start 0.12065 -0.2794)
			(end 0.12065 -0.3048)
			(stroke
				(width 0.1)
				(type default)
			)
			(layer "F.Fab")
		)
		(fp_line
			(start 0.12065 -0.3048)
			(end 0.67945 -0.3048)
			(stroke
				(width 0.1)
				(type default)
			)
			(layer "F.Fab")
		)
		(fp_line
			(start 0.120396 0.3048)
			(end 0.120396 0.2794)
			(stroke
				(width 0.1)
				(type default)
			)
			(layer "F.Fab")
		)
		(fp_line
			(start 0.120396 0.2794)
			(end -0.12065 0.2794)
			(stroke
				(width 0.1)
				(type default)
			)
			(layer "F.Fab")
		)
		(fp_line
			(start -0.12065 0.3048)
			(end -0.67945 0.3048)
			(stroke
				(width 0.1)
				(type default)
			)
			(layer "F.Fab")
		)
		(fp_line
			(start -0.12065 0.2794)
			(end -0.12065 0.3048)
			(stroke
				(width 0.1)
				(type default)
			)
			(layer "F.Fab")
		)
		(fp_line
			(start -0.12065 -0.2794)
			(end 0.12065 -0.2794)
			(stroke
				(width 0.1)
				(type default)
			)
			(layer "F.Fab")
		)
		(fp_line
			(start -0.12065 -0.305054)
			(end -0.12065 -0.2794)
			(stroke
				(width 0.1)
				(type default)
			)
			(layer "F.Fab")
		)
		(fp_line
			(start -0.67945 0.3048)
			(end -0.67945 -0.305054)
			(stroke
				(width 0.1)
				(type default)
			)
			(layer "F.Fab")
		)
		(fp_line
			(start -0.67945 -0.305054)
			(end -0.12065 -0.305054)
			(stroke
				(width 0.1)
				(type default)
			)
			(layer "F.Fab")
		)
		(pad "1" smd circle
			(at -0.40005 0 180)
			(size 0 0)
			(layers "F.Cu" "F.Mask" "F.Paste")
			(net "P3V3_AUX")
		)
		(pad "2" smd circle
			(at 0.40005 0 180)
			(size 0 0)
			(layers "F.Cu" "F.Mask" "F.Paste")
			(net "SWB_HSC_EN_BUF_R")
		)
	)
	(footprint ""
		(layer "F.Cu")
		(at 429.471836 -16.088614 90)
		(property "Reference" "C867"
			(at 0 0 90)
			(layer "F.SilkS")
			(hide yes)
			(effects
				(font
					(size 1.27 1.27)
				)
			)
		)
		(property "Value" ""
			(at 0 0 90)
			(layer "F.Fab")
			(effects
				(font
					(size 1.27 1.27)
				)
			)
		)
		(duplicate_pad_numbers_are_jumpers no)
		(fp_line
			(start 0.299974 -0.150114)
			(end 0.299974 0.150114)
			(stroke
				(width 0.1)
				(type default)
			)
			(layer "F.Fab")
		)
		(fp_line
			(start -0.299974 -0.150114)
			(end 0.299974 -0.150114)
			(stroke
				(width 0.1)
				(type default)
			)
			(layer "F.Fab")
		)
		(fp_line
			(start 0.299974 0.150114)
			(end -0.299974 0.150114)
			(stroke
				(width 0.1)
				(type default)
			)
			(layer "F.Fab")
		)
		(fp_line
			(start -0.299974 0.150114)
			(end -0.299974 -0.150114)
			(stroke
				(width 0.1)
				(type default)
			)
			(layer "F.Fab")
		)
		(pad "1" smd rect
			(at -0.2667 0 90)
			(size 0.3048 0.381)
			(layers "F.Cu" "F.Mask" "F.Paste")
			(net "P5E_CPU0_PE1_TX_C_DP<1>")
		)
		(pad "2" smd rect
			(at 0.2667 0 90)
			(size 0.3048 0.381)
			(layers "F.Cu" "F.Mask" "F.Paste")
			(net "P5E_CPU0_PE1_TX_DP<1>")
		)
	)
	(footprint ""
		(layer "F.Cu")
		(at 459.267814 -381.606552 179.946)
		(property "Reference" "PR91"
			(at 0 0 179.946)
			(layer "F.SilkS")
			(hide yes)
			(effects
				(font
					(size 1.27 1.27)
				)
			)
		)
		(property "Value" ""
			(at 0 0 179.946)
			(layer "F.Fab")
			(effects
				(font
					(size 1.27 1.27)
				)
			)
		)
		(duplicate_pad_numbers_are_jumpers no)
		(fp_line
			(start 0.787525 -0.40638)
			(end 0.787275 0.40642)
			(stroke
				(width 0.1524)
				(type default)
			)
			(layer "F.SilkS")
		)
		(fp_line
			(start 0.787275 0.40642)
			(end -0.787525 0.40638)
			(stroke
				(width 0.1524)
				(type default)
			)
			(layer "F.SilkS")
		)
		(fp_line
			(start -0.787275 -0.40642)
			(end 0.787525 -0.40638)
			(stroke
				(width 0.1524)
				(type default)
			)
			(layer "F.SilkS")
		)
		(fp_line
			(start -0.787525 0.40638)
			(end -0.787275 -0.40642)
			(stroke
				(width 0.1524)
				(type default)
			)
			(layer "F.SilkS")
		)
		(fp_line
			(start 0.679417 -0.304678)
			(end 0.679484 0.304922)
			(stroke
				(width 0.1)
				(type default)
			)
			(layer "F.Fab")
		)
		(fp_line
			(start 0.679484 0.304922)
			(end 0.120429 0.304687)
			(stroke
				(width 0.1)
				(type default)
			)
			(layer "F.Fab")
		)
		(fp_line
			(start 0.120641 -0.279514)
			(end 0.120617 -0.304914)
			(stroke
				(width 0.1)
				(type default)
			)
			(layer "F.Fab")
		)
		(fp_line
			(start 0.120617 -0.304914)
			(end 0.679417 -0.304678)
			(stroke
				(width 0.1)
				(type default)
			)
			(layer "F.Fab")
		)
		(fp_line
			(start 0.120429 0.304687)
			(end 0.120405 0.279287)
			(stroke
				(width 0.1)
				(type default)
			)
			(layer "F.Fab")
		)
		(fp_line
			(start 0.120405 0.279287)
			(end -0.120641 0.279514)
			(stroke
				(width 0.1)
				(type default)
			)
			(layer "F.Fab")
		)
		(fp_line
			(start -0.120659 -0.279286)
			(end 0.120641 -0.279514)
			(stroke
				(width 0.1)
				(type default)
			)
			(layer "F.Fab")
		)
		(fp_line
			(start -0.120683 -0.30494)
			(end -0.120659 -0.279286)
			(stroke
				(width 0.1)
				(type default)
			)
			(layer "F.Fab")
		)
		(fp_line
			(start -0.120617 0.304914)
			(end -0.679417 0.304678)
			(stroke
				(width 0.1)
				(type default)
			)
			(layer "F.Fab")
		)
		(fp_line
			(start -0.120641 0.279514)
			(end -0.120617 0.304914)
			(stroke
				(width 0.1)
				(type default)
			)
			(layer "F.Fab")
		)
		(fp_line
			(start -0.679484 -0.305176)
			(end -0.120683 -0.30494)
			(stroke
				(width 0.1)
				(type default)
			)
			(layer "F.Fab")
		)
		(fp_line
			(start -0.679417 0.304678)
			(end -0.679484 -0.305176)
			(stroke
				(width 0.1)
				(type default)
			)
			(layer "F.Fab")
		)
		(pad "1" smd circle
			(at -0.40005 0 179.946)
			(size 0 0)
			(layers "F.Cu" "F.Mask" "F.Paste")
			(net "P5V_AUX_FB")
		)
		(pad "2" smd circle
			(at 0.40005 0 179.946)
			(size 0 0)
			(layers "F.Cu" "F.Mask" "F.Paste")
			(net "GND")
		)
	)
)
